# S9S_MB_2U (Grand Teton) — schematic netlist excerpt (pin names and nets, part order shuffled) for the footprints in the layout excerpt that follows; sources: Cadence DE-HDL packaged netlist, KiCad conversion of 03242023_DA0F0TMBIJ0_F0T_Motherboard_J_brd_V01_OCP.brd

PC1684  Q_CAP  22UF 16V 20% X6S  pkg C0805  page 290 : A = SW_P12V_PVCCFA_EHV_FIVRA_CPU1_R ; B = GND
R1435  Q_RES  10K 1% CHIP  pkg 0402LF  page 220 : A = FM_ADR_TRIGGER_N ; B = P3V3_AUX
C1309  Q_CAP  10UF 6.3V 20% X6S  pkg C0603  page 210 : A = P3V3_AUX_CLK_GEN_VDDXTAL_CK440 ; B = GND

(kicad_pcb
	(version 20260206)
	(generator "pcbnew")
	(generator_version "10.0")
	(general
		(thickness 1.6)
		(legacy_teardrops no)
	)
	(paper "A4")
	(title_block
		(title "03242023_DA0F0TMBIJ0_F0T_Motherboard_J_brd_V01_OCP.brd")
		(comment 1 "Grand Teton / footprints 5482-5484 of 6105")
	)
	(layers
		(0 "F.Cu" signal "TOP")
		(4 "In1.Cu" signal "GND")
		(6 "In2.Cu" signal "IN1")
		(8 "In3.Cu" signal "GND1")
		(10 "In4.Cu" signal "IN2")
		(12 "In5.Cu" signal "GND2")
		(14 "In6.Cu" signal "IN3")
		(16 "In7.Cu" signal "GND3")
		(18 "In8.Cu" signal "VCC")
		(20 "In9.Cu" signal "VCC1")
		(22 "In10.Cu" signal "GND4")
		(24 "In11.Cu" signal "IN4")
		(26 "In12.Cu" signal "GND5")
		(28 "In13.Cu" signal "IN5")
		(30 "In14.Cu" signal "GND6")
		(32 "In15.Cu" signal "IN6")
		(34 "In16.Cu" signal "GND7")
		(2 "B.Cu" signal "BOTTOM")
		(9 "F.Adhes" user "F.Adhesive")
		(11 "B.Adhes" user "B.Adhesive")
		(13 "F.Paste" user "Package Geometry/Pastemask Top")
		(15 "B.Paste" user "Package Geometry/Pastemask Bottom")
		(5 "F.SilkS" user "Ref Des/Silkscreen Top")
		(7 "B.SilkS" user "Ref Des/Silkscreen Bottom")
		(1 "F.Mask" user "Board Geometry/Soldermask Top")
		(3 "B.Mask" user "Board Geometry/Soldermask Bottom")
		(17 "Dwgs.User" user "User.Drawings")
		(19 "Cmts.User" user "User.Comments")
		(21 "Eco1.User" user "User.Eco1")
		(23 "Eco2.User" user "User.Eco2")
		(25 "Edge.Cuts" user "Board Geometry/Outline")
		(27 "Margin" user)
		(31 "F.CrtYd" user "Package Geometry/Place Bound Top")
		(29 "B.CrtYd" user "Package Geometry/Place Bound Bottom")
		(35 "F.Fab" user "Ref Des/Assembly Top")
		(33 "B.Fab" user "Ref Des/Assembly Bottom")
	)
	(footprint ""
		(layer "B.Cu")
		(at 243.003832 -97.552764 -90)
		(property "Reference" "C1309"
			(at 0 0 90)
			(layer "B.SilkS")
			(hide yes)
			(effects
				(font
					(size 1.27 1.27)
				)
				(justify mirror)
			)
		)
		(property "Value" ""
			(at 0 0 90)
			(layer "B.Fab")
			(effects
				(font
					(size 1.27 1.27)
				)
				(justify mirror)
			)
		)
		(duplicate_pad_numbers_are_jumpers no)
		(fp_line
			(start -1.2954 0.5842)
			(end 1.2954 0.5842)
			(stroke
				(width 0.1524)
				(type default)
			)
			(layer "B.SilkS")
		)
		(fp_line
			(start 1.2954 0.5842)
			(end 1.2954 -0.5842)
			(stroke
				(width 0.1524)
				(type default)
			)
			(layer "B.SilkS")
		)
		(fp_line
			(start -1.2954 -0.5842)
			(end -1.2954 0.5842)
			(stroke
				(width 0.1524)
				(type default)
			)
			(layer "B.SilkS")
		)
		(fp_line
			(start 0 -0.5842)
			(end 0 0.5842)
			(stroke
				(width 0.1524)
				(type default)
			)
			(layer "B.SilkS")
		)
		(fp_line
			(start 1.2954 -0.5842)
			(end -1.2954 -0.5842)
			(stroke
				(width 0.1524)
				(type default)
			)
			(layer "B.SilkS")
		)
		(fp_line
			(start -0.8636 0.4572)
			(end 0.8636 0.4572)
			(stroke
				(width 0.1)
				(type default)
			)
			(layer "B.Fab")
		)
		(fp_line
			(start 0.8636 0.4572)
			(end 0.8636 0.4064)
			(stroke
				(width 0.1)
				(type default)
			)
			(layer "B.Fab")
		)
		(fp_line
			(start -1.1938 0.4064)
			(end -0.8636 0.4064)
			(stroke
				(width 0.1)
				(type default)
			)
			(layer "B.Fab")
		)
		(fp_line
			(start -0.8636 0.4064)
			(end -0.8636 0.4572)
			(stroke
				(width 0.1)
				(type default)
			)
			(layer "B.Fab")
		)
		(fp_line
			(start 0.8636 0.4064)
			(end 1.1938 0.4064)
			(stroke
				(width 0.1)
				(type default)
			)
			(layer "B.Fab")
		)
		(fp_line
			(start 1.1938 0.4064)
			(end 1.1938 -0.4064)
			(stroke
				(width 0.1)
				(type default)
			)
			(layer "B.Fab")
		)
		(fp_line
			(start -1.1938 -0.4064)
			(end -1.1938 0.4064)
			(stroke
				(width 0.1)
				(type default)
			)
			(layer "B.Fab")
		)
		(fp_line
			(start -0.8636 -0.4064)
			(end -1.1938 -0.4064)
			(stroke
				(width 0.1)
				(type default)
			)
			(layer "B.Fab")
		)
		(fp_line
			(start 0.8636 -0.4064)
			(end 0.8636 -0.4572)
			(stroke
				(width 0.1)
				(type default)
			)
			(layer "B.Fab")
		)
		(fp_line
			(start 1.1938 -0.4064)
			(end 0.8636 -0.4064)
			(stroke
				(width 0.1)
				(type default)
			)
			(layer "B.Fab")
		)
		(fp_line
			(start -0.8636 -0.4572)
			(end -0.8636 -0.4064)
			(stroke
				(width 0.1)
				(type default)
			)
			(layer "B.Fab")
		)
		(fp_line
			(start 0.8636 -0.4572)
			(end -0.8636 -0.4572)
			(stroke
				(width 0.1)
				(type default)
			)
			(layer "B.Fab")
		)
		(pad "1" smd rect
			(at 0.7366 0 180)
			(size 0.7112 0.8128)
			(layers "B.Cu" "B.Mask" "B.Paste")
			(net "P3V3_AUX_CLK_GEN_VDDXTAL_CK440")
		)
		(pad "2" smd rect
			(at -0.7366 0 180)
			(size 0.7112 0.8128)
			(layers "B.Cu" "B.Mask" "B.Paste")
			(net "GND")
		)
	)
	(footprint ""
		(layer "B.Cu")
		(at 193.60388 -103.685848 180)
		(property "Reference" "R1435"
			(at 0 0 0)
			(layer "B.SilkS")
			(hide yes)
			(effects
				(font
					(size 1.27 1.27)
				)
				(justify mirror)
			)
		)
		(property "Value" ""
			(at 0 0 0)
			(layer "B.Fab")
			(effects
				(font
					(size 1.27 1.27)
				)
				(justify mirror)
			)
		)
		(duplicate_pad_numbers_are_jumpers no)
		(fp_line
			(start 0.7874 0.4064)
			(end 0.7874 -0.4064)
			(stroke
				(width 0.1524)
				(type default)
			)
			(layer "B.SilkS")
		)
		(fp_line
			(start 0.7874 -0.4064)
			(end -0.7874 -0.4064)
			(stroke
				(width 0.1524)
				(type default)
			)
			(layer "B.SilkS")
		)
		(fp_line
			(start -0.7874 0.4064)
			(end 0.7874 0.4064)
			(stroke
				(width 0.1524)
				(type default)
			)
			(layer "B.SilkS")
		)
		(fp_line
			(start -0.7874 -0.4064)
			(end -0.7874 0.4064)
			(stroke
				(width 0.1524)
				(type default)
			)
			(layer "B.SilkS")
		)
		(fp_line
			(start 0.67945 0.3048)
			(end 0.67945 -0.305054)
			(stroke
				(width 0.1)
				(type default)
			)
			(layer "B.Fab")
		)
		(fp_line
			(start 0.67945 -0.305054)
			(end 0.12065 -0.305054)
			(stroke
				(width 0.1)
				(type default)
			)
			(layer "B.Fab")
		)
		(fp_line
			(start 0.12065 0.3048)
			(end 0.67945 0.3048)
			(stroke
				(width 0.1)
				(type default)
			)
			(layer "B.Fab")
		)
		(fp_line
			(start 0.12065 0.2794)
			(end 0.12065 0.3048)
			(stroke
				(width 0.1)
				(type default)
			)
			(layer "B.Fab")
		)
		(fp_line
			(start 0.12065 -0.2794)
			(end -0.12065 -0.2794)
			(stroke
				(width 0.1)
				(type default)
			)
			(layer "B.Fab")
		)
		(fp_line
			(start 0.12065 -0.305054)
			(end 0.12065 -0.2794)
			(stroke
				(width 0.1)
				(type default)
			)
			(layer "B.Fab")
		)
		(fp_line
			(start -0.120396 0.3048)
			(end -0.120396 0.2794)
			(stroke
				(width 0.1)
				(type default)
			)
			(layer "B.Fab")
		)
		(fp_line
			(start -0.120396 0.2794)
			(end 0.12065 0.2794)
			(stroke
				(width 0.1)
				(type default)
			)
			(layer "B.Fab")
		)
		(fp_line
			(start -0.12065 -0.2794)
			(end -0.12065 -0.3048)
			(stroke
				(width 0.1)
				(type default)
			)
			(layer "B.Fab")
		)
		(fp_line
			(start -0.12065 -0.3048)
			(end -0.67945 -0.3048)
			(stroke
				(width 0.1)
				(type default)
			)
			(layer "B.Fab")
		)
		(fp_line
			(start -0.67945 0.3048)
			(end -0.120396 0.3048)
			(stroke
				(width 0.1)
				(type default)
			)
			(layer "B.Fab")
		)
		(fp_line
			(start -0.67945 -0.3048)
			(end -0.67945 0.3048)
			(stroke
				(width 0.1)
				(type default)
			)
			(layer "B.Fab")
		)
		(pad "1" smd circle
			(at 0.40005 0)
			(size 0 0)
			(layers "B.Cu" "B.Mask" "B.Paste")
			(net "FM_ADR_TRIGGER_N")
		)
		(pad "2" smd circle
			(at -0.40005 0)
			(size 0 0)
			(layers "B.Cu" "B.Mask" "B.Paste")
			(net "P3V3_AUX")
		)
	)
	(footprint ""
		(layer "B.Cu")
		(at 187.04052 -358.11587 180)
		(property "Reference" "PC1684"
			(at 0 0 0)
			(layer "B.SilkS")
			(hide yes)
			(effects
				(font
					(size 1.27 1.27)
				)
				(justify mirror)
			)
		)
		(property "Value" ""
			(at 0 0 0)
			(layer "B.Fab")
			(effects
				(font
					(size 1.27 1.27)
				)
				(justify mirror)
			)
		)
		(duplicate_pad_numbers_are_jumpers no)
		(fp_line
			(start 1.524 0.762)
			(end 1.524 -0.762)
			(stroke
				(width 0.1524)
				(type default)
			)
			(layer "B.SilkS")
		)
		(fp_line
			(start 1.524 -0.762)
			(end -1.524 -0.762)
			(stroke
				(width 0.1524)
				(type default)
			)
			(layer "B.SilkS")
		)
		(fp_line
			(start -1.524 0.762)
			(end 1.524 0.762)
			(stroke
				(width 0.1524)
				(type default)
			)
			(layer "B.SilkS")
		)
		(fp_line
			(start -1.524 -0.762)
			(end -1.524 0.762)
			(stroke
				(width 0.1524)
				(type default)
			)
			(layer "B.SilkS")
		)
		(fp_line
			(start 1.1049 0.724916)
			(end -1.1049 0.724916)
			(stroke
				(width 0.1)
				(type default)
			)
			(layer "B.Fab")
		)
		(fp_line
			(start 1.1049 -0.724916)
			(end 1.1049 0.724916)
			(stroke
				(width 0.1)
				(type default)
			)
			(layer "B.Fab")
		)
		(fp_line
			(start -1.1049 0.724916)
			(end -1.1049 -0.724916)
			(stroke
				(width 0.1)
				(type default)
			)
			(layer "B.Fab")
		)
		(fp_line
			(start -1.1049 -0.724916)
			(end 1.1049 -0.724916)
			(stroke
				(width 0.1)
				(type default)
			)
			(layer "B.Fab")
		)
		(pad "1" smd rect
			(at 0.889 0 180)
			(size 1.016 1.27)
			(layers "B.Cu" "B.Mask" "B.Paste")
			(net "SW_P12V_PVCCFA_EHV_FIVRA_CPU1_R")
		)
		(pad "2" smd rect
			(at -0.889 0 180)
			(size 1.016 1.27)
			(layers "B.Cu" "B.Mask" "B.Paste")
			(net "GND")
		)
	)
)
